(kicad_pcb
	(version 20260206)
	(generator "pcbnew")
	(generator_version "10.0")
	(general
		(thickness 1.6)
		(legacy_teardrops no)
	)
	(paper "A4")
	(title_block
		(title "Bryce Canyon_R.DPB_16317-1_OCP.brd")
		(comment 1 "Bryce Canyon / footprints 337-343 of 2099")
	)
	(layers
		(0 "F.Cu" signal "TOP")
		(4 "In1.Cu" signal "L2GND")
		(6 "In2.Cu" signal "L3")
		(8 "In3.Cu" signal "L4VCC")
		(10 "In4.Cu" signal "L5VCC")
		(12 "In5.Cu" signal "L6")
		(14 "In6.Cu" signal "L7GND")
		(2 "B.Cu" signal "BOTTOM")
		(9 "F.Adhes" user "F.Adhesive")
		(11 "B.Adhes" user "B.Adhesive")
		(13 "F.Paste" user "Package Geometry/Pastemask Top")
		(15 "B.Paste" user "Package Geometry/Pastemask Bottom")
		(5 "F.SilkS" user "Ref Des/Silkscreen Top")
		(7 "B.SilkS" user "Ref Des/Silkscreen Bottom")
		(1 "F.Mask" user "Board Geometry/Soldermask Top")
		(3 "B.Mask" user "Board Geometry/Soldermask Bottom")
		(17 "Dwgs.User" user "User.Drawings")
		(19 "Cmts.User" user "User.Comments")
		(21 "Eco1.User" user "User.Eco1")
		(23 "Eco2.User" user "User.Eco2")
		(25 "Edge.Cuts" user "Board Geometry/Outline")
		(27 "Margin" user)
		(31 "F.CrtYd" user "Package Geometry/Place Bound Top")
		(29 "B.CrtYd" user "Package Geometry/Place Bound Bottom")
		(35 "F.Fab" user "Ref Des/Assembly Top")
		(33 "B.Fab" user "Ref Des/Assembly Bottom")
	)
	(footprint ""
		(layer "F.Cu")
		(at 461.80375 -102.503986 -90)
		(property "Reference" "R487"
			(at 0 0 270)
			(layer "F.SilkS")
			(hide yes)
			(effects
				(font
					(size 1.27 1.27)
				)
			)
		)
		(property "Value" "4K7R2F-GP"
			(at 0.064008 -3.993896 270)
			(unlocked yes)
			(layer "F.Fab")
			(hide yes)
			(effects
				(font
					(size 1.016 1.016)
					(thickness 0.1524)
				)
			)
		)
		(property "Device Type" "R402H16"
			(at 0.064008 -5.517896 270)
			(unlocked yes)
			(layer "F.Fab")
			(hide yes)
			(effects
				(font
					(size 1.016 1.016)
					(thickness 0.1524)
				)
			)
		)
		(duplicate_pad_numbers_are_jumpers no)
		(fp_line
			(start -0.508 -0.9398)
			(end -0.508 0.9398)
			(stroke
				(width 0.1524)
				(type default)
			)
			(layer "F.SilkS")
		)
		(fp_line
			(start 0.508 -0.9398)
			(end -0.508 -0.9398)
			(stroke
				(width 0.1524)
				(type default)
			)
			(layer "F.SilkS")
		)
		(fp_rect
			(start -0.508 0.9398)
			(end 0.508 -0.9398)
			(stroke
				(width 0)
				(type default)
			)
			(fill no)
			(layer "F.CrtYd")
		)
		(fp_rect
			(start -0.508 0.9398)
			(end 0.508 -0.9398)
			(stroke
				(width 0)
				(type default)
			)
			(fill no)
			(layer "F.Fab")
		)
		(pad "1" smd custom
			(at 0 -0.4445 270)
			(size 0.1397 0.1397)
			(layers "F.Cu" "F.Mask" "F.Paste")
			(net "DRIVE_B_23_FLT_LED")
			(options
				(clearance outline)
				(anchor circle)
			)
			(primitives
				(gr_poly
					(pts
						(arc
							(start -0.1778 -0.2794)
							(mid -0.249642 -0.249642)
							(end -0.2794 -0.1778)
						)
						(arc
							(start -0.2794 0.1778)
							(mid -0.249642 0.249642)
							(end -0.1778 0.2794)
						)
						(arc
							(start 0.1778 0.2794)
							(mid 0.249642 0.249642)
							(end 0.2794 0.1778)
						)
						(arc
							(start 0.2794 -0.1778)
							(mid 0.249642 -0.249642)
							(end 0.1778 -0.2794)
						)
					)
					(width 0)
					(fill yes)
				)
			)
		)
		(pad "2" smd custom
			(at 0 0.4445 270)
			(size 0.1397 0.1397)
			(layers "F.Cu" "F.Mask" "F.Paste")
			(net "GND")
			(options
				(clearance outline)
				(anchor circle)
			)
			(primitives
				(gr_poly
					(pts
						(arc
							(start -0.1778 -0.2794)
							(mid -0.249642 -0.249642)
							(end -0.2794 -0.1778)
						)
						(arc
							(start -0.2794 0.1778)
							(mid -0.249642 0.249642)
							(end -0.1778 0.2794)
						)
						(arc
							(start 0.1778 0.2794)
							(mid 0.249642 0.249642)
							(end 0.2794 0.1778)
						)
						(arc
							(start 0.2794 -0.1778)
							(mid 0.249642 -0.249642)
							(end 0.1778 -0.2794)
						)
					)
					(width 0)
					(fill yes)
				)
			)
		)
	)
	(footprint ""
		(layer "F.Cu")
		(at 136.457436 -362.795566 180)
		(property "Reference" "C525"
			(at 0 0 180)
			(layer "F.SilkS")
			(hide yes)
			(effects
				(font
					(size 1.27 1.27)
				)
			)
		)
		(property "Value" "SC22U25V0MX-2-GP"
			(at -0.00254 -4.78536 180)
			(unlocked yes)
			(layer "F.Fab")
			(hide yes)
			(effects
				(font
					(size 1.016 1.016)
					(thickness 0.1524)
				)
			)
		)
		(property "Device Type" "C1210H111"
			(at -0.00254 -6.38048 180)
			(unlocked yes)
			(layer "F.Fab")
			(hide yes)
			(effects
				(font
					(size 1.016 1.016)
					(thickness 0.1524)
				)
			)
		)
		(duplicate_pad_numbers_are_jumpers no)
		(fp_line
			(start 1.5748 2.3368)
			(end 1.5748 0.762)
			(stroke
				(width 0.1524)
				(type default)
			)
			(layer "F.SilkS")
		)
		(fp_line
			(start 1.5748 -0.762)
			(end 1.5748 -2.3368)
			(stroke
				(width 0.1524)
				(type default)
			)
			(layer "F.SilkS")
		)
		(fp_line
			(start 1.5748 -2.3368)
			(end -1.5748 -2.3368)
			(stroke
				(width 0.1524)
				(type default)
			)
			(layer "F.SilkS")
		)
		(fp_line
			(start -1.5748 2.3368)
			(end 1.5748 2.3368)
			(stroke
				(width 0.1524)
				(type default)
			)
			(layer "F.SilkS")
		)
		(fp_line
			(start -1.5748 0.762)
			(end -1.5748 2.3368)
			(stroke
				(width 0.1524)
				(type default)
			)
			(layer "F.SilkS")
		)
		(fp_line
			(start -1.5748 -2.3368)
			(end -1.5748 -0.762)
			(stroke
				(width 0.1524)
				(type default)
			)
			(layer "F.SilkS")
		)
		(fp_rect
			(start -1.651 2.413)
			(end 1.651 -2.413)
			(stroke
				(width 0)
				(type default)
			)
			(fill no)
			(layer "F.CrtYd")
		)
		(fp_poly
			(pts
				(xy 1.651 2.413) (xy 1.651 -2.413) (xy -1.651 -2.413) (xy -1.651 2.413)
			)
			(stroke
				(width 0)
				(type default)
			)
			(fill no)
			(layer "F.Fab")
		)
		(pad "1" smd rect
			(at 0 -1.4732 180)
			(size 2.794 1.397)
			(layers "F.Cu" "F.Mask" "F.Paste")
			(net "P12V_FAN1")
		)
		(pad "2" smd rect
			(at 0 1.4732 180)
			(size 2.794 1.397)
			(layers "F.Cu" "F.Mask" "F.Paste")
			(net "GND")
		)
	)
	(footprint ""
		(layer "F.Cu")
		(at 14.467586 -97.416112 -90)
		(property "Reference" "R341"
			(at 0 0 270)
			(layer "F.SilkS")
			(hide yes)
			(effects
				(font
					(size 1.27 1.27)
				)
			)
		)
		(property "Value" "4K7R2F-GP"
			(at 0.064008 -3.993896 270)
			(unlocked yes)
			(layer "F.Fab")
			(hide yes)
			(effects
				(font
					(size 1.016 1.016)
					(thickness 0.1524)
				)
			)
		)
		(property "Device Type" "R402H16"
			(at 0.064008 -5.517896 270)
			(unlocked yes)
			(layer "F.Fab")
			(hide yes)
			(effects
				(font
					(size 1.016 1.016)
					(thickness 0.1524)
				)
			)
		)
		(duplicate_pad_numbers_are_jumpers no)
		(fp_line
			(start -0.508 -0.9398)
			(end -0.508 0.9398)
			(stroke
				(width 0.1524)
				(type default)
			)
			(layer "F.SilkS")
		)
		(fp_line
			(start 0.508 -0.9398)
			(end -0.508 -0.9398)
			(stroke
				(width 0.1524)
				(type default)
			)
			(layer "F.SilkS")
		)
		(fp_rect
			(start -0.508 0.9398)
			(end 0.508 -0.9398)
			(stroke
				(width 0)
				(type default)
			)
			(fill no)
			(layer "F.CrtYd")
		)
		(fp_rect
			(start -0.508 0.9398)
			(end 0.508 -0.9398)
			(stroke
				(width 0)
				(type default)
			)
			(fill no)
			(layer "F.Fab")
		)
		(pad "1" smd custom
			(at 0 -0.4445 270)
			(size 0.1397 0.1397)
			(layers "F.Cu" "F.Mask" "F.Paste")
			(net "DRIVE_B_12_ACT")
			(options
				(clearance outline)
				(anchor circle)
			)
			(primitives
				(gr_poly
					(pts
						(arc
							(start -0.1778 -0.2794)
							(mid -0.249642 -0.249642)
							(end -0.2794 -0.1778)
						)
						(arc
							(start -0.2794 0.1778)
							(mid -0.249642 0.249642)
							(end -0.1778 0.2794)
						)
						(arc
							(start 0.1778 0.2794)
							(mid 0.249642 0.249642)
							(end 0.2794 0.1778)
						)
						(arc
							(start 0.2794 -0.1778)
							(mid 0.249642 -0.249642)
							(end 0.1778 -0.2794)
						)
					)
					(width 0)
					(fill yes)
				)
			)
		)
		(pad "2" smd custom
			(at 0 0.4445 270)
			(size 0.1397 0.1397)
			(layers "F.Cu" "F.Mask" "F.Paste")
			(net "GND")
			(options
				(clearance outline)
				(anchor circle)
			)
			(primitives
				(gr_poly
					(pts
						(arc
							(start -0.1778 -0.2794)
							(mid -0.249642 -0.249642)
							(end -0.2794 -0.1778)
						)
						(arc
							(start -0.2794 0.1778)
							(mid -0.249642 0.249642)
							(end -0.1778 0.2794)
						)
						(arc
							(start 0.1778 0.2794)
							(mid 0.249642 0.249642)
							(end 0.2794 0.1778)
						)
						(arc
							(start 0.2794 -0.1778)
							(mid 0.249642 -0.249642)
							(end 0.1778 -0.2794)
						)
					)
					(width 0)
					(fill yes)
				)
			)
		)
	)
	(footprint ""
		(layer "F.Cu")
		(at 244.348 -215.265)
		(property "Reference" "R86"
			(at 0 0 0)
			(layer "F.SilkS")
			(hide yes)
			(effects
				(font
					(size 1.27 1.27)
				)
			)
		)
		(property "Value" "4K7R2F-GP"
			(at 0.064008 -3.993896 0)
			(unlocked yes)
			(layer "F.Fab")
			(hide yes)
			(effects
				(font
					(size 1.016 1.016)
					(thickness 0.1524)
				)
			)
		)
		(property "Device Type" "R402H16"
			(at 0.064008 -5.517896 0)
			(unlocked yes)
			(layer "F.Fab")
			(hide yes)
			(effects
				(font
					(size 1.016 1.016)
					(thickness 0.1524)
				)
			)
		)
		(duplicate_pad_numbers_are_jumpers no)
		(fp_line
			(start -0.508 -0.9398)
			(end -0.508 0.9398)
			(stroke
				(width 0.1524)
				(type default)
			)
			(layer "F.SilkS")
		)
		(fp_line
			(start 0.508 -0.9398)
			(end -0.508 -0.9398)
			(stroke
				(width 0.1524)
				(type default)
			)
			(layer "F.SilkS")
		)
		(fp_rect
			(start -0.508 0.9398)
			(end 0.508 -0.9398)
			(stroke
				(width 0)
				(type default)
			)
			(fill no)
			(layer "F.CrtYd")
		)
		(fp_rect
			(start -0.508 0.9398)
			(end 0.508 -0.9398)
			(stroke
				(width 0)
				(type default)
			)
			(fill no)
			(layer "F.Fab")
		)
		(pad "1" smd custom
			(at 0 -0.4445)
			(size 0.1397 0.1397)
			(layers "F.Cu" "F.Mask" "F.Paste")
			(net "IO_EXP3_A2")
			(options
				(clearance outline)
				(anchor circle)
			)
			(primitives
				(gr_poly
					(pts
						(arc
							(start -0.1778 -0.2794)
							(mid -0.249642 -0.249642)
							(end -0.2794 -0.1778)
						)
						(arc
							(start -0.2794 0.1778)
							(mid -0.249642 0.249642)
							(end -0.1778 0.2794)
						)
						(arc
							(start 0.1778 0.2794)
							(mid 0.249642 0.249642)
							(end 0.2794 0.1778)
						)
						(arc
							(start 0.2794 -0.1778)
							(mid 0.249642 -0.249642)
							(end 0.1778 -0.2794)
						)
					)
					(width 0)
					(fill yes)
				)
			)
		)
		(pad "2" smd custom
			(at 0 0.4445)
			(size 0.1397 0.1397)
			(layers "F.Cu" "F.Mask" "F.Paste")
			(net "GND")
			(options
				(clearance outline)
				(anchor circle)
			)
			(primitives
				(gr_poly
					(pts
						(arc
							(start -0.1778 -0.2794)
							(mid -0.249642 -0.249642)
							(end -0.2794 -0.1778)
						)
						(arc
							(start -0.2794 0.1778)
							(mid -0.249642 0.249642)
							(end -0.1778 0.2794)
						)
						(arc
							(start 0.1778 0.2794)
							(mid 0.249642 0.249642)
							(end 0.2794 0.1778)
						)
						(arc
							(start 0.2794 -0.1778)
							(mid 0.249642 -0.249642)
							(end 0.1778 -0.2794)
						)
					)
					(width 0)
					(fill yes)
				)
			)
		)
	)
	(footprint ""
		(layer "F.Cu")
		(at 321.634612 -244.660674 -90)
		(property "Reference" "C107"
			(at 0 0 270)
			(layer "F.SilkS")
			(hide yes)
			(effects
				(font
					(size 1.27 1.27)
				)
			)
		)
		(property "Value" "SCD01U16V1KX-GP"
			(at -2.8321 -1.7399 270)
			(unlocked yes)
			(layer "F.Fab")
			(hide yes)
			(effects
				(font
					(size 1.016 1.016)
					(thickness 0.1524)
				)
			)
		)
		(property "Device Type" "C0201H13"
			(at -2.8321 -3.2639 270)
			(unlocked yes)
			(layer "F.Fab")
			(hide yes)
			(effects
				(font
					(size 1.016 1.016)
					(thickness 0.1524)
				)
			)
		)
		(duplicate_pad_numbers_are_jumpers no)
		(fp_rect
			(start -0.2794 0.6477)
			(end 0.2794 -0.6477)
			(stroke
				(width 0)
				(type default)
			)
			(fill no)
			(layer "F.CrtYd")
		)
		(fp_rect
			(start -0.2794 0.6477)
			(end 0.2794 -0.6477)
			(stroke
				(width 0)
				(type default)
			)
			(fill no)
			(layer "F.Fab")
		)
		(pad "1" smd custom
			(at 0 -0.2794 270)
			(size 0.0762 0.0762)
			(layers "F.Cu" "F.Mask" "F.Paste")
			(net "SAS_HDD_RX_P6")
			(options
				(clearance outline)
				(anchor circle)
			)
			(primitives
				(gr_poly
					(pts
						(arc
							(start 0.1524 -0.127)
							(mid 0.137521 -0.162921)
							(end 0.1016 -0.1778)
						)
						(arc
							(start -0.1016 -0.1778)
							(mid -0.137521 -0.162921)
							(end -0.1524 -0.127)
						)
						(arc
							(start -0.1524 0.127)
							(mid -0.137521 0.162921)
							(end -0.1016 0.1778)
						)
						(arc
							(start 0.1016 0.1778)
							(mid 0.137521 0.162921)
							(end 0.1524 0.127)
						)
					)
					(width 0)
					(fill yes)
				)
			)
		)
		(pad "2" smd custom
			(at 0 0.2794 270)
			(size 0.0762 0.0762)
			(layers "F.Cu" "F.Mask" "F.Paste")
			(net "PHY_SCC_B_TO_DRV_B_6_DP")
			(options
				(clearance outline)
				(anchor circle)
			)
			(primitives
				(gr_poly
					(pts
						(arc
							(start 0.1524 -0.127)
							(mid 0.137521 -0.162921)
							(end 0.1016 -0.1778)
						)
						(arc
							(start -0.1016 -0.1778)
							(mid -0.137521 -0.162921)
							(end -0.1524 -0.127)
						)
						(arc
							(start -0.1524 0.127)
							(mid -0.137521 0.162921)
							(end -0.1016 0.1778)
						)
						(arc
							(start 0.1016 0.1778)
							(mid 0.137521 0.162921)
							(end 0.1524 0.127)
						)
					)
					(width 0)
					(fill yes)
				)
			)
		)
	)
	(footprint ""
		(layer "F.Cu")
		(at 143.256 -214.249)
		(property "Reference" "R268"
			(at 0 0 0)
			(layer "F.SilkS")
			(hide yes)
			(effects
				(font
					(size 1.27 1.27)
				)
			)
		)
		(property "Value" "130R3F-GP"
			(at -0.0254 -2.5146 0)
			(unlocked yes)
			(layer "F.Fab")
			(hide yes)
			(effects
				(font
					(size 1.016 1.016)
					(thickness 0.1524)
				)
			)
		)
		(property "Device Type" "R603H22"
			(at -0.0254 -4.0386 0)
			(unlocked yes)
			(layer "F.Fab")
			(hide yes)
			(effects
				(font
					(size 1.016 1.016)
					(thickness 0.1524)
				)
			)
		)
		(duplicate_pad_numbers_are_jumpers no)
		(fp_line
			(start -0.4826 0)
			(end -0.2032 0)
			(stroke
				(width 0.2032)
				(type default)
			)
			(layer "F.SilkS")
		)
		(fp_line
			(start 0.2032 0)
			(end 0.4826 0)
			(stroke
				(width 0.2032)
				(type default)
			)
			(layer "F.SilkS")
		)
		(fp_rect
			(start -0.5842 1.3335)
			(end 0.5842 -1.3335)
			(stroke
				(width 0)
				(type default)
			)
			(fill no)
			(layer "F.CrtYd")
		)
		(fp_rect
			(start -0.5842 1.3335)
			(end 0.5842 -1.3335)
			(stroke
				(width 0)
				(type default)
			)
			(fill no)
			(layer "F.Fab")
		)
		(pad "1" smd custom
			(at 0 -0.762)
			(size 0.2159 0.2159)
			(layers "F.Cu" "F.Mask" "F.Paste")
			(net "P5V_B_1")
			(options
				(clearance outline)
				(anchor circle)
			)
			(primitives
				(gr_poly
					(pts
						(arc
							(start -0.3302 -0.4318)
							(mid -0.402042 -0.402042)
							(end -0.4318 -0.3302)
						)
						(arc
							(start -0.4318 0.3302)
							(mid -0.402042 0.402042)
							(end -0.3302 0.4318)
						)
						(arc
							(start 0.3302 0.4318)
							(mid 0.402042 0.402042)
							(end 0.4318 0.3302)
						)
						(arc
							(start 0.4318 -0.3302)
							(mid 0.402042 -0.402042)
							(end 0.3302 -0.4318)
						)
					)
					(width 0)
					(fill yes)
				)
			)
		)
		(pad "2" smd custom
			(at 0 0.762)
			(size 0.2159 0.2159)
			(layers "F.Cu" "F.Mask" "F.Paste")
			(net "FLT_HDD4")
			(options
				(clearance outline)
				(anchor circle)
			)
			(primitives
				(gr_poly
					(pts
						(arc
							(start -0.3302 -0.4318)
							(mid -0.402042 -0.402042)
							(end -0.4318 -0.3302)
						)
						(arc
							(start -0.4318 0.3302)
							(mid -0.402042 0.402042)
							(end -0.3302 0.4318)
						)
						(arc
							(start 0.3302 0.4318)
							(mid 0.402042 0.402042)
							(end 0.4318 0.3302)
						)
						(arc
							(start 0.4318 -0.3302)
							(mid 0.402042 -0.402042)
							(end 0.3302 -0.4318)
						)
					)
					(width 0)
					(fill yes)
				)
			)
		)
	)
	(footprint ""
		(layer "F.Cu")
		(at 115.2398 -11.303 -90)
		(property "Reference" "R707"
			(at 0 0 270)
			(layer "F.SilkS")
			(hide yes)
			(effects
				(font
					(size 1.27 1.27)
				)
			)
		)
		(property "Value" "200KR2F-L-GP"
			(at 0.064008 -3.993896 270)
			(unlocked yes)
			(layer "F.Fab")
			(hide yes)
			(effects
				(font
					(size 1.016 1.016)
					(thickness 0.1524)
				)
			)
		)
		(property "Device Type" "R402H16"
			(at 0.064008 -5.517896 270)
			(unlocked yes)
			(layer "F.Fab")
			(hide yes)
			(effects
				(font
					(size 1.016 1.016)
					(thickness 0.1524)
				)
			)
		)
		(duplicate_pad_numbers_are_jumpers no)
		(fp_line
			(start -0.508 -0.9398)
			(end -0.508 0.9398)
			(stroke
				(width 0.1524)
				(type default)
			)
			(layer "F.SilkS")
		)
		(fp_line
			(start 0.508 -0.9398)
			(end -0.508 -0.9398)
			(stroke
				(width 0.1524)
				(type default)
			)
			(layer "F.SilkS")
		)
		(fp_rect
			(start -0.508 0.9398)
			(end 0.508 -0.9398)
			(stroke
				(width 0)
				(type default)
			)
			(fill no)
			(layer "F.CrtYd")
		)
		(fp_rect
			(start -0.508 0.9398)
			(end 0.508 -0.9398)
			(stroke
				(width 0)
				(type default)
			)
			(fill no)
			(layer "F.Fab")
		)
		(pad "1" smd custom
			(at 0 -0.4445 270)
			(size 0.1397 0.1397)
			(layers "F.Cu" "F.Mask" "F.Paste")
			(net "SW_HDD_R27")
			(options
				(clearance outline)
				(anchor circle)
			)
			(primitives
				(gr_poly
					(pts
						(arc
							(start -0.1778 -0.2794)
							(mid -0.249642 -0.249642)
							(end -0.2794 -0.1778)
						)
						(arc
							(start -0.2794 0.1778)
							(mid -0.249642 0.249642)
							(end -0.1778 0.2794)
						)
						(arc
							(start 0.1778 0.2794)
							(mid 0.249642 0.249642)
							(end 0.2794 0.1778)
						)
						(arc
							(start 0.2794 -0.1778)
							(mid 0.249642 -0.249642)
							(end 0.1778 -0.2794)
						)
					)
					(width 0)
					(fill yes)
				)
			)
		)
		(pad "2" smd custom
			(at 0 0.4445 270)
			(size 0.1397 0.1397)
			(layers "F.Cu" "F.Mask" "F.Paste")
			(net "SW_HDD_N27")
			(options
				(clearance outline)
				(anchor circle)
			)
			(primitives
				(gr_poly
					(pts
						(arc
							(start -0.1778 -0.2794)
							(mid -0.249642 -0.249642)
							(end -0.2794 -0.1778)
						)
						(arc
							(start -0.2794 0.1778)
							(mid -0.249642 0.249642)
							(end -0.1778 0.2794)
						)
						(arc
							(start 0.1778 0.2794)
							(mid 0.249642 0.249642)
							(end 0.2794 0.1778)
						)
						(arc
							(start 0.2794 -0.1778)
							(mid 0.249642 -0.249642)
							(end 0.1778 -0.2794)
						)
					)
					(width 0)
					(fill yes)
				)
			)
		)
	)
)
